#ISCELL
  mstr_misc dns *
  *
#ISCELL
  pure_quanta quanta_title_block_c *
  *
#ISCELL
  standard offpage *
  page147_i1
#CELL
  pure_quanta q_res *
  page147_i11
#ISCELL
  logical_power universal_gnd *
  page147_i13
#ISCELL
  standard offpage *
  page147_i14
#CELL
  pure_quanta q_cap *
  page147_i15
#ISCELL
  logical_power universal_gnd *
  page147_i16
#ISCELL
  logical_power universal_power *
  page147_i17
#CELL
  pure_quanta q_res *
  page147_i18
#ISCELL
  logical_power universal_gnd *
  page147_i19
#ISCELL
  standard offpage *
  page147_i2
#CELL
  pure_quanta mosfet_nch_dual *
  page147_i20
#ISCELL
  standard offpage *
  page147_i21
#CELL
  pure_quanta q_cap *
  page147_i22
#ISCELL
  logical_power universal_gnd *
  page147_i23
#ISCELL
  logical_power universal_power *
  page147_i24
#CELL
  pure_quanta q_res *
  page147_i25
#CELL
  pure_quanta mosfet_nch_dual *
  page147_i26
#ISCELL
  logical_power universal_gnd *
  page147_i27
#CELL
  pure_quanta q_res *
  page147_i28
#ISCELL
  logical_power universal_power *
  page147_i29
#ISCELL
  standard offpage *
  page147_i3
#ISCELL
  logical_power universal_gnd *
  page147_i30
#CELL
  pure_quanta mosfet_nch_dual *
  page147_i31
#ISCELL
  logical_power universal_power *
  page147_i32
#CELL
  pure_quanta q_res *
  page147_i33
#CELL
  pure_quanta q_res *
  page147_i34
#ISCELL
  logical_power universal_power *
  page147_i35
#CELL
  pure_quanta q_res *
  page147_i36
#ISCELL
  logical_power universal_gnd *
  page147_i37
#CELL
  pure_quanta mosfet_nch_dual *
  page147_i38
#ISCELL
  logical_power universal_gnd *
  page147_i39
#ISCELL
  standard offpage *
  page147_i4
#ISCELL
  logical_power universal_power *
  page147_i40
#CELL
  pure_quanta q_res *
  page147_i41
#CELL
  pure_quanta q_res *
  page147_i42
#ISCELL
  logical_power universal_gnd *
  page147_i43
#ISCELL
  standard offpage *
  page147_i44
#ISCELL
  standard offpage *
  page147_i45
#ISCELL
  standard offpage *
  page147_i46
#CELL
  pure_quanta q_cap *
  page147_i47
#ISCELL
  logical_power universal_gnd *
  page147_i48
#ISCELL
  logical_power universal_power *
  page147_i49
#CELL
  pure_quanta q_res *
  page147_i5
#CELL
  pure_quanta q_res *
  page147_i50
#CELL
  pure_quanta mosfet_nch_dual *
  page147_i51
#ISCELL
  logical_power universal_gnd *
  page147_i52
#ISCELL
  logical_power universal_power *
  page147_i53
#CELL
  pure_quanta q_res *
  page147_i54
#CELL
  pure_quanta mosfet_nch_dual *
  page147_i55
#ISCELL
  logical_power universal_gnd *
  page147_i56
#ISCELL
  logical_power universal_power *
  page147_i57
#CELL
  pure_quanta q_res *
  page147_i58
#ISCELL
  standard offpage *
  page147_i59
#CELL
  pure_quanta q_res *
  page147_i6
#CELL
  pure_quanta q_res *
  page147_i60
#ISCELL
  logical_power universal_gnd *
  page147_i61
#CELL
  pure_quanta mosfet_nch_dual *
  page147_i62
#ISCELL
  standard offpage *
  page147_i63
#ISCELL
  logical_power universal_power *
  page147_i64
#CELL
  pure_quanta q_res *
  page147_i65
#CELL
  pure_quanta q_cap *
  page147_i66
#ISCELL
  logical_power universal_gnd *
  page147_i67
#ISCELL
  logical_power universal_gnd *
  page147_i68
#ISCELL
  logical_power universal_power *
  page147_i69
#CELL
  pure_quanta q_res *
  page147_i7
#CELL
  pure_quanta q_res *
  page147_i70
#CELL
  pure_quanta mosfet_nch_dual *
  page147_i71
#ISCELL
  logical_power universal_gnd *
  page147_i72
#ISCELL
  logical_power universal_power *
  page147_i74
#CELL
  pure_quanta q_res *
  page147_i75
#CELL
  pure_quanta q_res *
  page147_i76
#ISCELL
  logical_power universal_gnd *
  page147_i77
#ISCELL
  standard offpage *
  page147_i78
#CELL
  pure_quanta q_res *
  page147_i8
#ISCELL
  standard offpage *
  page147_i9
